(kicad_pcb
	(version 20260206)
	(generator "pcbnew")
	(generator_version "10.0")
	(general
		(thickness 1.6)
		(legacy_teardrops no)
	)
	(paper "A4")
	(title_block
		(title "04192023_DAF0TMB3IC0_F0TG_MB_C_brd_V02_OCP.brd")
		(comment 1 "Grand Teton / footprints 2824-2830 of 8354")
	)
	(layers
		(0 "F.Cu" signal "TOP")
		(4 "In1.Cu" signal "GND")
		(6 "In2.Cu" signal "IN1")
		(8 "In3.Cu" signal "GND1")
		(10 "In4.Cu" signal "IN2")
		(12 "In5.Cu" signal "GND2")
		(14 "In6.Cu" signal "IN3")
		(16 "In7.Cu" signal "GND3")
		(18 "In8.Cu" signal "VCC")
		(20 "In9.Cu" signal "VCC1")
		(22 "In10.Cu" signal "GND4")
		(24 "In11.Cu" signal "IN4")
		(26 "In12.Cu" signal "GND5")
		(28 "In13.Cu" signal "IN5")
		(30 "In14.Cu" signal "GND6")
		(32 "In15.Cu" signal "IN6")
		(34 "In16.Cu" signal "GND7")
		(2 "B.Cu" signal "BOTTOM")
		(9 "F.Adhes" user "F.Adhesive")
		(11 "B.Adhes" user "B.Adhesive")
		(13 "F.Paste" user "Package Geometry/Pastemask Top")
		(15 "B.Paste" user "Package Geometry/Pastemask Bottom")
		(5 "F.SilkS" user "Ref Des/Silkscreen Top")
		(7 "B.SilkS" user "Ref Des/Silkscreen Bottom")
		(1 "F.Mask" user "Board Geometry/Soldermask Top")
		(3 "B.Mask" user "Board Geometry/Soldermask Bottom")
		(17 "Dwgs.User" user "User.Drawings")
		(19 "Cmts.User" user "User.Comments")
		(21 "Eco1.User" user "User.Eco1")
		(23 "Eco2.User" user "User.Eco2")
		(25 "Edge.Cuts" user "Board Geometry/Outline")
		(27 "Margin" user)
		(31 "F.CrtYd" user "Package Geometry/Place Bound Top")
		(29 "B.CrtYd" user "Package Geometry/Place Bound Bottom")
		(35 "F.Fab" user "Ref Des/Assembly Top")
		(33 "B.Fab" user "Ref Des/Assembly Bottom")
	)
	(footprint ""
		(layer "F.Cu")
		(at 434.796692 -19.625818 -90)
		(property "Reference" "R1929"
			(at 0 0 270)
			(layer "F.SilkS")
			(hide yes)
			(effects
				(font
					(size 1.27 1.27)
				)
			)
		)
		(property "Value" ""
			(at 0 0 270)
			(layer "F.Fab")
			(effects
				(font
					(size 1.27 1.27)
				)
			)
		)
		(duplicate_pad_numbers_are_jumpers no)
		(fp_line
			(start -0.7874 0.4064)
			(end -0.7874 -0.4064)
			(stroke
				(width 0.1524)
				(type default)
			)
			(layer "F.SilkS")
		)
		(fp_line
			(start 0.7874 0.4064)
			(end -0.7874 0.4064)
			(stroke
				(width 0.1524)
				(type default)
			)
			(layer "F.SilkS")
		)
		(fp_line
			(start -0.7874 -0.4064)
			(end 0.7874 -0.4064)
			(stroke
				(width 0.1524)
				(type default)
			)
			(layer "F.SilkS")
		)
		(fp_line
			(start 0.7874 -0.4064)
			(end 0.7874 0.4064)
			(stroke
				(width 0.1524)
				(type default)
			)
			(layer "F.SilkS")
		)
		(fp_line
			(start -0.67945 0.3048)
			(end -0.67945 -0.305054)
			(stroke
				(width 0.1)
				(type default)
			)
			(layer "F.Fab")
		)
		(fp_line
			(start -0.12065 0.3048)
			(end -0.67945 0.3048)
			(stroke
				(width 0.1)
				(type default)
			)
			(layer "F.Fab")
		)
		(fp_line
			(start 0.120396 0.3048)
			(end 0.120396 0.2794)
			(stroke
				(width 0.1)
				(type default)
			)
			(layer "F.Fab")
		)
		(fp_line
			(start 0.67945 0.3048)
			(end 0.120396 0.3048)
			(stroke
				(width 0.1)
				(type default)
			)
			(layer "F.Fab")
		)
		(fp_line
			(start -0.12065 0.2794)
			(end -0.12065 0.3048)
			(stroke
				(width 0.1)
				(type default)
			)
			(layer "F.Fab")
		)
		(fp_line
			(start 0.120396 0.2794)
			(end -0.12065 0.2794)
			(stroke
				(width 0.1)
				(type default)
			)
			(layer "F.Fab")
		)
		(fp_line
			(start -0.12065 -0.2794)
			(end 0.12065 -0.2794)
			(stroke
				(width 0.1)
				(type default)
			)
			(layer "F.Fab")
		)
		(fp_line
			(start 0.12065 -0.2794)
			(end 0.12065 -0.3048)
			(stroke
				(width 0.1)
				(type default)
			)
			(layer "F.Fab")
		)
		(fp_line
			(start 0.12065 -0.3048)
			(end 0.67945 -0.3048)
			(stroke
				(width 0.1)
				(type default)
			)
			(layer "F.Fab")
		)
		(fp_line
			(start 0.67945 -0.3048)
			(end 0.67945 0.3048)
			(stroke
				(width 0.1)
				(type default)
			)
			(layer "F.Fab")
		)
		(fp_line
			(start -0.67945 -0.305054)
			(end -0.12065 -0.305054)
			(stroke
				(width 0.1)
				(type default)
			)
			(layer "F.Fab")
		)
		(fp_line
			(start -0.12065 -0.305054)
			(end -0.12065 -0.2794)
			(stroke
				(width 0.1)
				(type default)
			)
			(layer "F.Fab")
		)
		(pad "1" smd circle
			(at -0.40005 0 270)
			(size 0 0)
			(layers "F.Cu" "F.Mask" "F.Paste")
			(net "GND")
		)
		(pad "2" smd circle
			(at 0.40005 0 270)
			(size 0 0)
			(layers "F.Cu" "F.Mask" "F.Paste")
			(net "OCP_SFF_AUX_PWR_EN")
		)
	)
	(footprint ""
		(layer "F.Cu")
		(at 171.26966 -388.753604 180)
		(property "Reference" "L32"
			(at 0 0 180)
			(layer "F.SilkS")
			(hide yes)
			(effects
				(font
					(size 1.27 1.27)
				)
			)
		)
		(property "Value" ""
			(at 0 0 180)
			(layer "F.Fab")
			(effects
				(font
					(size 1.27 1.27)
				)
			)
		)
		(duplicate_pad_numbers_are_jumpers no)
		(fp_line
			(start 0.762 0.381)
			(end -0.762 0.381)
			(stroke
				(width 0.1524)
				(type default)
			)
			(layer "F.SilkS")
		)
		(fp_line
			(start 0.762 -0.381)
			(end 0.762 0.381)
			(stroke
				(width 0.1524)
				(type default)
			)
			(layer "F.SilkS")
		)
		(fp_line
			(start -0.762 0.381)
			(end -0.762 -0.381)
			(stroke
				(width 0.1524)
				(type default)
			)
			(layer "F.SilkS")
		)
		(fp_line
			(start -0.762 -0.381)
			(end 0.762 -0.381)
			(stroke
				(width 0.1524)
				(type default)
			)
			(layer "F.SilkS")
		)
		(fp_line
			(start 0.680466 0.306324)
			(end 0.118364 0.306324)
			(stroke
				(width 0.1)
				(type default)
			)
			(layer "F.Fab")
		)
		(fp_line
			(start 0.680466 -0.306324)
			(end 0.680466 0.306324)
			(stroke
				(width 0.1)
				(type default)
			)
			(layer "F.Fab")
		)
		(fp_line
			(start 0.118872 -0.2794)
			(end 0.118872 -0.306324)
			(stroke
				(width 0.1)
				(type default)
			)
			(layer "F.Fab")
		)
		(fp_line
			(start 0.118872 -0.306324)
			(end 0.680466 -0.306324)
			(stroke
				(width 0.1)
				(type default)
			)
			(layer "F.Fab")
		)
		(fp_line
			(start 0.118364 0.306324)
			(end 0.118364 0.2794)
			(stroke
				(width 0.1)
				(type default)
			)
			(layer "F.Fab")
		)
		(fp_line
			(start 0.118364 0.2794)
			(end -0.119634 0.2794)
			(stroke
				(width 0.1)
				(type default)
			)
			(layer "F.Fab")
		)
		(fp_line
			(start -0.118364 -0.2794)
			(end 0.118872 -0.2794)
			(stroke
				(width 0.1)
				(type default)
			)
			(layer "F.Fab")
		)
		(fp_line
			(start -0.118364 -0.307086)
			(end -0.118364 -0.2794)
			(stroke
				(width 0.1)
				(type default)
			)
			(layer "F.Fab")
		)
		(fp_line
			(start -0.119634 0.30607)
			(end -0.681736 0.30607)
			(stroke
				(width 0.1)
				(type default)
			)
			(layer "F.Fab")
		)
		(fp_line
			(start -0.119634 0.2794)
			(end -0.119634 0.30607)
			(stroke
				(width 0.1)
				(type default)
			)
			(layer "F.Fab")
		)
		(fp_line
			(start -0.681736 0.30607)
			(end -0.681736 -0.307086)
			(stroke
				(width 0.1)
				(type default)
			)
			(layer "F.Fab")
		)
		(fp_line
			(start -0.681736 -0.307086)
			(end -0.118364 -0.307086)
			(stroke
				(width 0.1)
				(type default)
			)
			(layer "F.Fab")
		)
		(pad "1" smd rect
			(at -0.40005 0)
			(size 0.4572 0.508)
			(layers "F.Cu" "F.Mask" "F.Paste")
			(net "P1V8_CPU1_RT_1D")
		)
		(pad "2" smd rect
			(at 0.40005 0)
			(size 0.4572 0.508)
			(layers "F.Cu" "F.Mask" "F.Paste")
			(net "P1V8_CPU1_RT2_1A_1D")
		)
	)
	(footprint ""
		(layer "F.Cu")
		(at 345.8337 -15.924276 90)
		(property "Reference" "D49"
			(at -3.1496 0.230632 90)
			(unlocked yes)
			(layer "F.SilkS")
			(effects
				(font
					(size 0.7874 0.5842)
					(thickness 0.1524)
				)
				(justify left)
			)
		)
		(property "Value" ""
			(at 0 0 90)
			(layer "F.Fab")
			(effects
				(font
					(size 1.27 1.27)
				)
			)
		)
		(duplicate_pad_numbers_are_jumpers no)
		(fp_line
			(start 1.16078 -0.4826)
			(end 1.16078 0.4826)
			(stroke
				(width 0.1524)
				(type default)
			)
			(layer "F.SilkS")
		)
		(fp_line
			(start 1.03378 -0.4826)
			(end 1.03378 0.4826)
			(stroke
				(width 0.1524)
				(type default)
			)
			(layer "F.SilkS")
		)
		(fp_line
			(start 0.90678 -0.4826)
			(end 0.90678 0.4826)
			(stroke
				(width 0.1524)
				(type default)
			)
			(layer "F.SilkS")
		)
		(fp_line
			(start -0.64008 -0.4826)
			(end 1.16078 -0.4826)
			(stroke
				(width 0.1524)
				(type default)
			)
			(layer "F.SilkS")
		)
		(fp_line
			(start -0.79248 -0.4826)
			(end 1.03378 -0.4826)
			(stroke
				(width 0.1524)
				(type default)
			)
			(layer "F.SilkS")
		)
		(fp_line
			(start -0.89408 -0.4826)
			(end 0.90678 -0.4826)
			(stroke
				(width 0.1524)
				(type default)
			)
			(layer "F.SilkS")
		)
		(fp_line
			(start 1.16078 0.4826)
			(end -0.64008 0.4826)
			(stroke
				(width 0.1524)
				(type default)
			)
			(layer "F.SilkS")
		)
		(fp_line
			(start 1.03378 0.4826)
			(end -0.79248 0.4826)
			(stroke
				(width 0.1524)
				(type default)
			)
			(layer "F.SilkS")
		)
		(fp_line
			(start 0.90678 0.4826)
			(end -0.90678 0.4826)
			(stroke
				(width 0.1524)
				(type default)
			)
			(layer "F.SilkS")
		)
		(fp_line
			(start -0.90678 0.4826)
			(end -0.90678 -0.4699)
			(stroke
				(width 0.1524)
				(type default)
			)
			(layer "F.SilkS")
		)
		(fp_line
			(start 0.499872 -0.249936)
			(end 0.499872 0.249936)
			(stroke
				(width 0.1)
				(type default)
			)
			(layer "F.Fab")
		)
		(fp_line
			(start -0.499872 -0.249936)
			(end 0.499872 -0.249936)
			(stroke
				(width 0.1)
				(type default)
			)
			(layer "F.Fab")
		)
		(fp_line
			(start 0.499872 0.249936)
			(end -0.499872 0.249936)
			(stroke
				(width 0.1)
				(type default)
			)
			(layer "F.Fab")
		)
		(fp_line
			(start -0.499872 0.249936)
			(end -0.499872 -0.249936)
			(stroke
				(width 0.1)
				(type default)
			)
			(layer "F.Fab")
		)
		(pad "A" smd rect
			(at -0.47498 0 90)
			(size 0.6096 0.7112)
			(layers "F.Cu" "F.Mask" "F.Paste")
			(net "P5V_STBY_PWR_LED")
		)
		(pad "C" smd rect
			(at 0.47498 0 90)
			(size 0.6096 0.7112)
			(layers "F.Cu" "F.Mask" "F.Paste")
			(net "GND")
		)
	)
	(footprint ""
		(layer "F.Cu")
		(at 360.190542 -399.034)
		(property "Reference" "R1397"
			(at 0 0 0)
			(layer "F.SilkS")
			(hide yes)
			(effects
				(font
					(size 1.27 1.27)
				)
			)
		)
		(property "Value" ""
			(at 0 0 0)
			(layer "F.Fab")
			(effects
				(font
					(size 1.27 1.27)
				)
			)
		)
		(duplicate_pad_numbers_are_jumpers no)
		(fp_line
			(start -0.32512 -0.175006)
			(end 0.32512 -0.175006)
			(stroke
				(width 0.1)
				(type default)
			)
			(layer "F.Fab")
		)
		(fp_line
			(start -0.32512 0.175006)
			(end -0.32512 -0.175006)
			(stroke
				(width 0.1)
				(type default)
			)
			(layer "F.Fab")
		)
		(fp_line
			(start 0.32512 -0.175006)
			(end 0.32512 0.175006)
			(stroke
				(width 0.1)
				(type default)
			)
			(layer "F.Fab")
		)
		(fp_line
			(start 0.32512 0.175006)
			(end -0.32512 0.175006)
			(stroke
				(width 0.1)
				(type default)
			)
			(layer "F.Fab")
		)
		(pad "1" smd rect
			(at -0.2667 0)
			(size 0.3048 0.381)
			(layers "F.Cu" "F.Mask" "F.Paste")
			(net "P1V8_CPU0_RT_1D")
		)
		(pad "2" smd rect
			(at 0.2667 0 180)
			(size 0.3048 0.381)
			(layers "F.Cu" "F.Mask" "F.Paste")
			(net "RXDET_BYP_RT_CPU0_P1")
		)
	)
	(footprint ""
		(layer "F.Cu")
		(at 370.905278 -146.552158 180)
		(property "Reference" "R8286"
			(at 0 0 180)
			(layer "F.SilkS")
			(hide yes)
			(effects
				(font
					(size 1.27 1.27)
				)
			)
		)
		(property "Value" ""
			(at 0 0 180)
			(layer "F.Fab")
			(effects
				(font
					(size 1.27 1.27)
				)
			)
		)
		(duplicate_pad_numbers_are_jumpers no)
		(fp_line
			(start 0.7874 0.4064)
			(end -0.7874 0.4064)
			(stroke
				(width 0.1524)
				(type default)
			)
			(layer "F.SilkS")
		)
		(fp_line
			(start 0.7874 -0.4064)
			(end 0.7874 0.4064)
			(stroke
				(width 0.1524)
				(type default)
			)
			(layer "F.SilkS")
		)
		(fp_line
			(start -0.7874 0.4064)
			(end -0.7874 -0.4064)
			(stroke
				(width 0.1524)
				(type default)
			)
			(layer "F.SilkS")
		)
		(fp_line
			(start -0.7874 -0.4064)
			(end 0.7874 -0.4064)
			(stroke
				(width 0.1524)
				(type default)
			)
			(layer "F.SilkS")
		)
		(fp_line
			(start 0.67945 0.3048)
			(end 0.120396 0.3048)
			(stroke
				(width 0.1)
				(type default)
			)
			(layer "F.Fab")
		)
		(fp_line
			(start 0.67945 -0.3048)
			(end 0.67945 0.3048)
			(stroke
				(width 0.1)
				(type default)
			)
			(layer "F.Fab")
		)
		(fp_line
			(start 0.12065 -0.2794)
			(end 0.12065 -0.3048)
			(stroke
				(width 0.1)
				(type default)
			)
			(layer "F.Fab")
		)
		(fp_line
			(start 0.12065 -0.3048)
			(end 0.67945 -0.3048)
			(stroke
				(width 0.1)
				(type default)
			)
			(layer "F.Fab")
		)
		(fp_line
			(start 0.120396 0.3048)
			(end 0.120396 0.2794)
			(stroke
				(width 0.1)
				(type default)
			)
			(layer "F.Fab")
		)
		(fp_line
			(start 0.120396 0.2794)
			(end -0.12065 0.2794)
			(stroke
				(width 0.1)
				(type default)
			)
			(layer "F.Fab")
		)
		(fp_line
			(start -0.12065 0.3048)
			(end -0.67945 0.3048)
			(stroke
				(width 0.1)
				(type default)
			)
			(layer "F.Fab")
		)
		(fp_line
			(start -0.12065 0.2794)
			(end -0.12065 0.3048)
			(stroke
				(width 0.1)
				(type default)
			)
			(layer "F.Fab")
		)
		(fp_line
			(start -0.12065 -0.2794)
			(end 0.12065 -0.2794)
			(stroke
				(width 0.1)
				(type default)
			)
			(layer "F.Fab")
		)
		(fp_line
			(start -0.12065 -0.305054)
			(end -0.12065 -0.2794)
			(stroke
				(width 0.1)
				(type default)
			)
			(layer "F.Fab")
		)
		(fp_line
			(start -0.67945 0.3048)
			(end -0.67945 -0.305054)
			(stroke
				(width 0.1)
				(type default)
			)
			(layer "F.Fab")
		)
		(fp_line
			(start -0.67945 -0.305054)
			(end -0.12065 -0.305054)
			(stroke
				(width 0.1)
				(type default)
			)
			(layer "F.Fab")
		)
		(pad "1" smd circle
			(at -0.40005 0 180)
			(size 0 0)
			(layers "F.Cu" "F.Mask" "F.Paste")
			(net "SVID_PVDDCR_CPU0_P0_SVTO")
		)
		(pad "2" smd circle
			(at 0.40005 0 180)
			(size 0 0)
			(layers "F.Cu" "F.Mask" "F.Paste")
			(net "GND")
		)
	)
	(footprint ""
		(layer "F.Cu")
		(at 405.753062 -57.2135)
		(property "Reference" "C85"
			(at 0 0 0)
			(layer "F.SilkS")
			(hide yes)
			(effects
				(font
					(size 1.27 1.27)
				)
			)
		)
		(property "Value" ""
			(at 0 0 0)
			(layer "F.Fab")
			(effects
				(font
					(size 1.27 1.27)
				)
			)
		)
		(duplicate_pad_numbers_are_jumpers no)
		(fp_line
			(start -0.7874 -0.4064)
			(end 0.7874 -0.4064)
			(stroke
				(width 0.1524)
				(type default)
			)
			(layer "F.SilkS")
		)
		(fp_line
			(start -0.7874 0.4064)
			(end -0.7874 -0.4064)
			(stroke
				(width 0.1524)
				(type default)
			)
			(layer "F.SilkS")
		)
		(fp_line
			(start 0.7874 -0.4064)
			(end 0.7874 0.4064)
			(stroke
				(width 0.1524)
				(type default)
			)
			(layer "F.SilkS")
		)
		(fp_line
			(start 0.7874 0.4064)
			(end -0.7874 0.4064)
			(stroke
				(width 0.1524)
				(type default)
			)
			(layer "F.SilkS")
		)
		(fp_line
			(start -0.67945 -0.305054)
			(end -0.12065 -0.305054)
			(stroke
				(width 0.1)
				(type default)
			)
			(layer "F.Fab")
		)
		(fp_line
			(start -0.67945 0.3048)
			(end -0.67945 -0.305054)
			(stroke
				(width 0.1)
				(type default)
			)
			(layer "F.Fab")
		)
		(fp_line
			(start -0.12065 -0.305054)
			(end -0.12065 -0.2794)
			(stroke
				(width 0.1)
				(type default)
			)
			(layer "F.Fab")
		)
		(fp_line
			(start -0.12065 -0.2794)
			(end 0.12065 -0.2794)
			(stroke
				(width 0.1)
				(type default)
			)
			(layer "F.Fab")
		)
		(fp_line
			(start -0.12065 0.2794)
			(end -0.12065 0.3048)
			(stroke
				(width 0.1)
				(type default)
			)
			(layer "F.Fab")
		)
		(fp_line
			(start -0.12065 0.3048)
			(end -0.67945 0.3048)
			(stroke
				(width 0.1)
				(type default)
			)
			(layer "F.Fab")
		)
		(fp_line
			(start 0.120396 0.2794)
			(end -0.12065 0.2794)
			(stroke
				(width 0.1)
				(type default)
			)
			(layer "F.Fab")
		)
		(fp_line
			(start 0.120396 0.3048)
			(end 0.120396 0.2794)
			(stroke
				(width 0.1)
				(type default)
			)
			(layer "F.Fab")
		)
		(fp_line
			(start 0.12065 -0.3048)
			(end 0.67945 -0.3048)
			(stroke
				(width 0.1)
				(type default)
			)
			(layer "F.Fab")
		)
		(fp_line
			(start 0.12065 -0.2794)
			(end 0.12065 -0.3048)
			(stroke
				(width 0.1)
				(type default)
			)
			(layer "F.Fab")
		)
		(fp_line
			(start 0.67945 -0.3048)
			(end 0.67945 0.3048)
			(stroke
				(width 0.1)
				(type default)
			)
			(layer "F.Fab")
		)
		(fp_line
			(start 0.67945 0.3048)
			(end 0.120396 0.3048)
			(stroke
				(width 0.1)
				(type default)
			)
			(layer "F.Fab")
		)
		(pad "1" smd circle
			(at -0.40005 0)
			(size 0 0)
			(layers "F.Cu" "F.Mask" "F.Paste")
			(net "HDT_HDR_TRST_N")
		)
		(pad "2" smd circle
			(at 0.40005 0)
			(size 0 0)
			(layers "F.Cu" "F.Mask" "F.Paste")
			(net "GND")
		)
	)
	(footprint ""
		(layer "F.Cu")
		(at 115.189 -415.29 180)
		(property "Reference" "Q75"
			(at -3.272282 -1.210564 90)
			(unlocked yes)
			(layer "F.SilkS")
			(effects
				(font
					(size 0.7874 0.5842)
					(thickness 0.1524)
				)
				(justify left)
			)
		)
		(property "Value" ""
			(at 0 0 180)
			(layer "F.Fab")
			(effects
				(font
					(size 1.27 1.27)
				)
			)
		)
		(duplicate_pad_numbers_are_jumpers no)
		(fp_line
			(start 1.332738 1.100074)
			(end -1.332738 1.100074)
			(stroke
				(width 0.1524)
				(type default)
			)
			(layer "F.SilkS")
		)
		(fp_line
			(start 1.332738 -1.100074)
			(end 1.332738 1.100074)
			(stroke
				(width 0.1524)
				(type default)
			)
			(layer "F.SilkS")
		)
		(fp_line
			(start 0.4826 -1.100074)
			(end 1.332738 -1.100074)
			(stroke
				(width 0.1524)
				(type default)
			)
			(layer "F.SilkS")
		)
		(fp_line
			(start 0 -0.541274)
			(end 0.4826 -1.100074)
			(stroke
				(width 0.1524)
				(type default)
			)
			(layer "F.SilkS")
		)
		(fp_line
			(start -0.4826 -1.100074)
			(end 0 -0.541274)
			(stroke
				(width 0.1524)
				(type default)
			)
			(layer "F.SilkS")
		)
		(fp_line
			(start -1.332738 1.100074)
			(end -1.332738 -1.100074)
			(stroke
				(width 0.1524)
				(type default)
			)
			(layer "F.SilkS")
		)
		(fp_line
			(start -1.332738 -1.100074)
			(end -0.4826 -1.100074)
			(stroke
				(width 0.1524)
				(type default)
			)
			(layer "F.SilkS")
		)
		(fp_poly
			(pts
				(xy -1.533144 -0.649986) (xy -2.2352 -0.298958) (xy -2.2352 -1.001014)
			)
			(stroke
				(width 0)
				(type default)
			)
			(fill yes)
			(layer "F.SilkS")
		)
		(fp_line
			(start 0.674878 1.100074)
			(end -0.674878 1.100074)
			(stroke
				(width 0.1)
				(type default)
			)
			(layer "F.Fab")
		)
		(fp_line
			(start 0.674878 -1.100074)
			(end 0.674878 1.100074)
			(stroke
				(width 0.1)
				(type default)
			)
			(layer "F.Fab")
		)
		(fp_line
			(start -0.674878 1.100074)
			(end -0.674878 -1.100074)
			(stroke
				(width 0.1)
				(type default)
			)
			(layer "F.Fab")
		)
		(fp_line
			(start -0.674878 -1.100074)
			(end 0.674878 -1.100074)
			(stroke
				(width 0.1)
				(type default)
			)
			(layer "F.Fab")
		)
		(fp_poly
			(pts
				(xy -2.2352 -0.298958) (xy -2.2352 -1.001014) (xy -1.533144 -0.649986)
			)
			(stroke
				(width 0)
				(type default)
			)
			(fill yes)
			(layer "F.Fab")
		)
		(pad "1" smd rect
			(at -0.94996 -0.649986 270)
			(size 0.4318 0.508)
			(layers "F.Cu" "F.Mask" "F.Paste")
			(net "GND")
		)
		(pad "2" smd rect
			(at -0.94996 0 270)
			(size 0.4318 0.508)
			(layers "F.Cu" "F.Mask" "F.Paste")
			(net "FM_SMB_1_ALERT_GPU_N")
		)
		(pad "3" smd rect
			(at -0.94996 0.649986 270)
			(size 0.4318 0.508)
			(layers "F.Cu" "F.Mask" "F.Paste")
			(net "FM_SMB_1_ALERT_GPU_ISO_N")
		)
		(pad "4" smd rect
			(at 0.94996 0.649986 270)
			(size 0.4318 0.508)
			(layers "F.Cu" "F.Mask" "F.Paste")
			(net "GND")
		)
		(pad "5" smd rect
			(at 0.94996 0 270)
			(size 0.4318 0.508)
			(layers "F.Cu" "F.Mask" "F.Paste")
			(net "FM_SMB_1_ALERT_GPU")
		)
		(pad "6" smd rect
			(at 0.94996 -0.649986 270)
			(size 0.4318 0.508)
			(layers "F.Cu" "F.Mask" "F.Paste")
			(net "FM_SMB_1_ALERT_GPU")
		)
	)
)
